(kicad_pcb
	(version 20260206)
	(generator "pcbnew")
	(generator_version "10.0")
	(general
		(thickness 1.6)
		(legacy_teardrops no)
	)
	(paper "A4")
	(title_block
		(title "panther-plus-userver — 13130-1b_20150205.brd")
		(comment 1 "Honey Badger (Wiwynn) / footprint 406 of 1509 (DIMM2), pads 65-71 of 210")
	)
	(layers
		(0 "F.Cu" signal "TOP")
		(4 "In1.Cu" signal "L2")
		(6 "In2.Cu" signal "L3")
		(8 "In3.Cu" signal "L4")
		(10 "In4.Cu" signal "L5")
		(12 "In5.Cu" signal "L6")
		(14 "In6.Cu" signal "L7")
		(16 "In7.Cu" signal "L8")
		(18 "In8.Cu" signal "L9")
		(20 "In9.Cu" signal "L10")
		(22 "In10.Cu" signal "L11")
		(2 "B.Cu" signal "BOTTOM")
		(9 "F.Adhes" user "F.Adhesive")
		(11 "B.Adhes" user "B.Adhesive")
		(13 "F.Paste" user "Package Geometry/Pastemask Top")
		(15 "B.Paste" user "Package Geometry/Pastemask Bottom")
		(5 "F.SilkS" user "Ref Des/Silkscreen Top")
		(7 "B.SilkS" user "Ref Des/Silkscreen Bottom")
		(1 "F.Mask" user "Board Geometry/Soldermask Top")
		(3 "B.Mask" user "Board Geometry/Soldermask Bottom")
		(17 "Dwgs.User" user "User.Drawings")
		(19 "Cmts.User" user "User.Comments")
		(21 "Eco1.User" user "User.Eco1")
		(23 "Eco2.User" user "User.Eco2")
		(25 "Edge.Cuts" user "Board Geometry/Outline")
		(27 "Margin" user)
		(31 "F.CrtYd" user "Package Geometry/Place Bound Top")
		(29 "B.CrtYd" user "Package Geometry/Place Bound Bottom")
		(35 "F.Fab" user "Ref Des/Assembly Top")
		(33 "B.Fab" user "Ref Des/Assembly Bottom")
	)
	(footprint ""
		(layer "F.Cu")
		(at 158.500064 -66.699892 180)
		(property "Reference" "DIMM2"
			(at 0 0 180)
			(layer "F.SilkS")
			(hide yes)
			(effects
				(font
					(size 1.27 1.27)
				)
			)
		)
		(property "Value" "DDR3-204P-174-COLAY-1-GP"
			(at -40.682164 -17.468088 180)
			(unlocked yes)
			(layer "F.Fab")
			(hide yes)
			(effects
				(font
					(size 1.016 1.016)
					(thickness 0.1524)
				)
			)
		)
		(property "Device Type" "AS0A626-H8SN-7H-COLAY-1"
			(at -40.682164 -18.992088 180)
			(unlocked yes)
			(layer "F.Fab")
			(hide yes)
			(effects
				(font
					(size 1.016 1.016)
					(thickness 0.1524)
				)
			)
		)
		(duplicate_pad_numbers_are_jumpers no)
		(pad "63" smd custom
			(at -13.050012 4.106672 180)
			(size 0.1143 0.1143)
			(layers "F.Cu" "F.Mask" "F.Paste")
			(net "M_A_DQ30")
			(options
				(clearance outline)
				(anchor circle)
			)
			(primitives
				(gr_poly
					(pts
						(xy 0 0.9017) (xy -0.03175 0.89916) (xy -0.0635 0.889) (xy -0.09144 0.87376) (xy -0.11684 0.85344)
						(xy -0.13716 0.82804) (xy -0.1524 0.8001) (xy -0.16256 0.76835) (xy -0.1651 0.7366) (xy -0.1651 0.11938)
						(xy -0.17272 0.11176) (xy -0.19812 0.0762) (xy -0.2032 0.06604) (xy -0.20701 0.05715) (xy -0.21209 0.04699)
						(xy -0.2159 0.03683) (xy -0.21844 0.02667) (xy -0.22225 0.01524) (xy -0.22352 0.00508) (xy -0.22606 -0.00508)
						(xy -0.22733 -0.01651) (xy -0.22733 -0.02667) (xy -0.2286 -0.0381) (xy -0.22733 -0.04953) (xy -0.22733 -0.05969)
						(xy -0.22606 -0.07112) (xy -0.22352 -0.08128) (xy -0.22225 -0.09144) (xy -0.21844 -0.10287) (xy -0.2159 -0.11303)
						(xy -0.21209 -0.12319) (xy -0.20701 -0.13335) (xy -0.2032 -0.14224) (xy -0.19812 -0.1524) (xy -0.17272 -0.18796)
						(xy -0.1651 -0.19558) (xy -0.1651 -0.7366) (xy -0.16256 -0.76835) (xy -0.1524 -0.8001) (xy -0.13716 -0.82804)
						(xy -0.11684 -0.85344) (xy -0.09144 -0.87376) (xy -0.0635 -0.889) (xy -0.03175 -0.89916) (xy 0 -0.9017)
						(xy 0.03175 -0.89916) (xy 0.0635 -0.889) (xy 0.09144 -0.87376) (xy 0.11684 -0.85344) (xy 0.13716 -0.82804)
						(xy 0.1524 -0.8001) (xy 0.16256 -0.76835) (xy 0.1651 -0.7366) (xy 0.1651 -0.19685) (xy 0.17272 -0.18923)
						(xy 0.17907 -0.18034) (xy 0.18669 -0.17145) (xy 0.19177 -0.16256) (xy 0.19812 -0.15367) (xy 0.20828 -0.13335)
						(xy 0.21971 -0.10287) (xy 0.22225 -0.09271) (xy 0.22479 -0.08128) (xy 0.22606 -0.07112) (xy 0.2286 -0.05969)
						(xy 0.2286 -0.01651) (xy 0.22606 -0.00508) (xy 0.22479 0.00508) (xy 0.22225 0.01651) (xy 0.21971 0.02667)
						(xy 0.20828 0.05715) (xy 0.19812 0.07747) (xy 0.19177 0.08636) (xy 0.18669 0.09525) (xy 0.17907 0.10414)
						(xy 0.17272 0.11303) (xy 0.1651 0.12065) (xy 0.1651 0.7366) (xy 0.16256 0.76835) (xy 0.1524 0.8001)
						(xy 0.13716 0.82804) (xy 0.11684 0.85344) (xy 0.09144 0.87376) (xy 0.0635 0.889) (xy 0.03175 0.89916)
					)
					(width 0)
					(fill yes)
				)
			)
		)
		(pad "64" smd custom
			(at -12.750038 -4.106672 180)
			(size 0.1143 0.1143)
			(layers "F.Cu" "F.Mask" "F.Paste")
			(net "GND")
			(options
				(clearance outline)
				(anchor circle)
			)
			(primitives
				(gr_poly
					(pts
						(xy 0 0.9017) (xy -0.03175 0.89916) (xy -0.0635 0.889) (xy -0.09144 0.87376) (xy -0.11684 0.85344)
						(xy -0.13716 0.82804) (xy -0.1524 0.8001) (xy -0.16256 0.76835) (xy -0.1651 0.7366) (xy -0.1651 0.19685)
						(xy -0.17272 0.18923) (xy -0.17907 0.18034) (xy -0.18669 0.17145) (xy -0.19177 0.16256) (xy -0.19812 0.15367)
						(xy -0.20828 0.13335) (xy -0.21971 0.10287) (xy -0.22225 0.09271) (xy -0.22479 0.08128) (xy -0.22606 0.07112)
						(xy -0.2286 0.05969) (xy -0.2286 0.01651) (xy -0.22606 0.00508) (xy -0.22479 -0.00508) (xy -0.22225 -0.01651)
						(xy -0.21971 -0.02667) (xy -0.20828 -0.05715) (xy -0.19812 -0.07747) (xy -0.19177 -0.08636) (xy -0.18669 -0.09525)
						(xy -0.17907 -0.10414) (xy -0.17272 -0.11303) (xy -0.1651 -0.12065) (xy -0.1651 -0.7366) (xy -0.16256 -0.76835)
						(xy -0.1524 -0.8001) (xy -0.13716 -0.82804) (xy -0.11684 -0.85344) (xy -0.09144 -0.87376) (xy -0.0635 -0.889)
						(xy -0.03175 -0.89916) (xy 0 -0.9017) (xy 0.03175 -0.89916) (xy 0.0635 -0.889) (xy 0.09144 -0.87376)
						(xy 0.11684 -0.85344) (xy 0.13716 -0.82804) (xy 0.1524 -0.8001) (xy 0.16256 -0.76835) (xy 0.1651 -0.7366)
						(xy 0.1651 -0.11938) (xy 0.17272 -0.11176) (xy 0.19812 -0.0762) (xy 0.2032 -0.06604) (xy 0.20701 -0.05715)
						(xy 0.21209 -0.04699) (xy 0.2159 -0.03683) (xy 0.21844 -0.02667) (xy 0.22225 -0.01524) (xy 0.22352 -0.00508)
						(xy 0.22606 0.00508) (xy 0.22733 0.01651) (xy 0.22733 0.02667) (xy 0.2286 0.0381) (xy 0.22733 0.04953)
						(xy 0.22733 0.05969) (xy 0.22606 0.07112) (xy 0.22352 0.08128) (xy 0.22225 0.09144) (xy 0.21844 0.10287)
						(xy 0.2159 0.11303) (xy 0.21209 0.12319) (xy 0.20701 0.13335) (xy 0.2032 0.14224) (xy 0.19812 0.1524)
						(xy 0.17272 0.18796) (xy 0.1651 0.19558) (xy 0.1651 0.7366) (xy 0.16256 0.76835) (xy 0.1524 0.8001)
						(xy 0.13716 0.82804) (xy 0.11684 0.85344) (xy 0.09144 0.87376) (xy 0.0635 0.889) (xy 0.03175 0.89916)
					)
					(width 0)
					(fill yes)
				)
			)
		)
		(pad "65" smd custom
			(at -12.450064 4.106672 180)
			(size 0.1143 0.1143)
			(layers "F.Cu" "F.Mask" "F.Paste")
			(net "M_A_DQ31")
			(options
				(clearance outline)
				(anchor circle)
			)
			(primitives
				(gr_poly
					(pts
						(xy 0 0.9017) (xy -0.03175 0.89916) (xy -0.0635 0.889) (xy -0.09144 0.87376) (xy -0.11684 0.85344)
						(xy -0.13716 0.82804) (xy -0.1524 0.8001) (xy -0.16256 0.76835) (xy -0.1651 0.7366) (xy -0.1651 -0.13462)
						(xy -0.17272 -0.14224) (xy -0.19812 -0.1778) (xy -0.2032 -0.18796) (xy -0.20701 -0.19685) (xy -0.21209 -0.20701)
						(xy -0.2159 -0.21717) (xy -0.21844 -0.22733) (xy -0.22225 -0.23876) (xy -0.22352 -0.24892) (xy -0.22606 -0.25908)
						(xy -0.22733 -0.27051) (xy -0.22733 -0.28067) (xy -0.2286 -0.2921) (xy -0.22733 -0.30353) (xy -0.22733 -0.31369)
						(xy -0.22606 -0.32512) (xy -0.22352 -0.33528) (xy -0.22225 -0.34544) (xy -0.21844 -0.35687) (xy -0.2159 -0.36703)
						(xy -0.21209 -0.37719) (xy -0.20701 -0.38735) (xy -0.2032 -0.39624) (xy -0.19812 -0.4064) (xy -0.17272 -0.44196)
						(xy -0.1651 -0.44958) (xy -0.1651 -0.7366) (xy -0.16256 -0.76835) (xy -0.1524 -0.8001) (xy -0.13716 -0.82804)
						(xy -0.11684 -0.85344) (xy -0.09144 -0.87376) (xy -0.0635 -0.889) (xy -0.03175 -0.89916) (xy 0 -0.9017)
						(xy 0.03175 -0.89916) (xy 0.0635 -0.889) (xy 0.09144 -0.87376) (xy 0.11684 -0.85344) (xy 0.13716 -0.82804)
						(xy 0.1524 -0.8001) (xy 0.16256 -0.76835) (xy 0.1651 -0.7366) (xy 0.1651 -0.44958) (xy 0.17272 -0.44196)
						(xy 0.19812 -0.4064) (xy 0.2032 -0.39624) (xy 0.20701 -0.38735) (xy 0.21209 -0.37719) (xy 0.2159 -0.36703)
						(xy 0.21844 -0.35687) (xy 0.22225 -0.34544) (xy 0.22352 -0.33528) (xy 0.22606 -0.32512) (xy 0.22733 -0.31369)
						(xy 0.22733 -0.30353) (xy 0.2286 -0.2921) (xy 0.22733 -0.28067) (xy 0.22733 -0.27051) (xy 0.22606 -0.25908)
						(xy 0.22352 -0.24892) (xy 0.22225 -0.23876) (xy 0.21844 -0.22733) (xy 0.2159 -0.21717) (xy 0.21209 -0.20701)
						(xy 0.20701 -0.19685) (xy 0.2032 -0.18796) (xy 0.19812 -0.1778) (xy 0.17272 -0.14224) (xy 0.1651 -0.13462)
						(xy 0.1651 0.7366) (xy 0.16256 0.76835) (xy 0.1524 0.8001) (xy 0.13716 0.82804) (xy 0.11684 0.85344)
						(xy 0.09144 0.87376) (xy 0.0635 0.889) (xy 0.03175 0.89916)
					)
					(width 0)
					(fill yes)
				)
			)
		)
		(pad "66" smd custom
			(at -12.15009 -4.106672 180)
			(size 0.1143 0.1143)
			(layers "F.Cu" "F.Mask" "F.Paste")
			(net "M_A_DQ26")
			(options
				(clearance outline)
				(anchor circle)
			)
			(primitives
				(gr_poly
					(pts
						(xy 0 0.9017) (xy -0.03175 0.89916) (xy -0.0635 0.889) (xy -0.09144 0.87376) (xy -0.11684 0.85344)
						(xy -0.13716 0.82804) (xy -0.1524 0.8001) (xy -0.16256 0.76835) (xy -0.1651 0.7366) (xy -0.1651 0.44958)
						(xy -0.17272 0.44196) (xy -0.19812 0.4064) (xy -0.2032 0.39624) (xy -0.20701 0.38735) (xy -0.21209 0.37719)
						(xy -0.2159 0.36703) (xy -0.21844 0.35687) (xy -0.22225 0.34544) (xy -0.22352 0.33528) (xy -0.22606 0.32512)
						(xy -0.22733 0.31369) (xy -0.22733 0.30353) (xy -0.2286 0.2921) (xy -0.22733 0.28067) (xy -0.22733 0.27051)
						(xy -0.22606 0.25908) (xy -0.22352 0.24892) (xy -0.22225 0.23876) (xy -0.21844 0.22733) (xy -0.2159 0.21717)
						(xy -0.21209 0.20701) (xy -0.20701 0.19685) (xy -0.2032 0.18796) (xy -0.19812 0.1778) (xy -0.17272 0.14224)
						(xy -0.1651 0.13462) (xy -0.1651 -0.7366) (xy -0.16256 -0.76835) (xy -0.1524 -0.8001) (xy -0.13716 -0.82804)
						(xy -0.11684 -0.85344) (xy -0.09144 -0.87376) (xy -0.0635 -0.889) (xy -0.03175 -0.89916) (xy 0 -0.9017)
						(xy 0.03175 -0.89916) (xy 0.0635 -0.889) (xy 0.09144 -0.87376) (xy 0.11684 -0.85344) (xy 0.13716 -0.82804)
						(xy 0.1524 -0.8001) (xy 0.16256 -0.76835) (xy 0.1651 -0.7366) (xy 0.1651 0.13462) (xy 0.17272 0.14224)
						(xy 0.19812 0.1778) (xy 0.2032 0.18796) (xy 0.20701 0.19685) (xy 0.21209 0.20701) (xy 0.2159 0.21717)
						(xy 0.21844 0.22733) (xy 0.22225 0.23876) (xy 0.22352 0.24892) (xy 0.22606 0.25908) (xy 0.22733 0.27051)
						(xy 0.22733 0.28067) (xy 0.2286 0.2921) (xy 0.22733 0.30353) (xy 0.22733 0.31369) (xy 0.22606 0.32512)
						(xy 0.22352 0.33528) (xy 0.22225 0.34544) (xy 0.21844 0.35687) (xy 0.2159 0.36703) (xy 0.21209 0.37719)
						(xy 0.20701 0.38735) (xy 0.2032 0.39624) (xy 0.19812 0.4064) (xy 0.17272 0.44196) (xy 0.1651 0.44958)
						(xy 0.1651 0.7366) (xy 0.16256 0.76835) (xy 0.1524 0.8001) (xy 0.13716 0.82804) (xy 0.11684 0.85344)
						(xy 0.09144 0.87376) (xy 0.0635 0.889) (xy 0.03175 0.89916)
					)
					(width 0)
					(fill yes)
				)
			)
		)
		(pad "67" smd custom
			(at -11.850116 4.106672 180)
			(size 0.1143 0.1143)
			(layers "F.Cu" "F.Mask" "F.Paste")
			(net "GND")
			(options
				(clearance outline)
				(anchor circle)
			)
			(primitives
				(gr_poly
					(pts
						(xy 0 0.9017) (xy -0.03175 0.89916) (xy -0.0635 0.889) (xy -0.09144 0.87376) (xy -0.11684 0.85344)
						(xy -0.13716 0.82804) (xy -0.1524 0.8001) (xy -0.16256 0.76835) (xy -0.1651 0.7366) (xy -0.1651 0.11938)
						(xy -0.17272 0.11176) (xy -0.19812 0.0762) (xy -0.2032 0.06604) (xy -0.20701 0.05715) (xy -0.21209 0.04699)
						(xy -0.2159 0.03683) (xy -0.21844 0.02667) (xy -0.22225 0.01524) (xy -0.22352 0.00508) (xy -0.22606 -0.00508)
						(xy -0.22733 -0.01651) (xy -0.22733 -0.02667) (xy -0.2286 -0.0381) (xy -0.22733 -0.04953) (xy -0.22733 -0.05969)
						(xy -0.22606 -0.07112) (xy -0.22352 -0.08128) (xy -0.22225 -0.09144) (xy -0.21844 -0.10287) (xy -0.2159 -0.11303)
						(xy -0.21209 -0.12319) (xy -0.20701 -0.13335) (xy -0.2032 -0.14224) (xy -0.19812 -0.1524) (xy -0.17272 -0.18796)
						(xy -0.1651 -0.19558) (xy -0.1651 -0.7366) (xy -0.16256 -0.76835) (xy -0.1524 -0.8001) (xy -0.13716 -0.82804)
						(xy -0.11684 -0.85344) (xy -0.09144 -0.87376) (xy -0.0635 -0.889) (xy -0.03175 -0.89916) (xy 0 -0.9017)
						(xy 0.03175 -0.89916) (xy 0.0635 -0.889) (xy 0.09144 -0.87376) (xy 0.11684 -0.85344) (xy 0.13716 -0.82804)
						(xy 0.1524 -0.8001) (xy 0.16256 -0.76835) (xy 0.1651 -0.7366) (xy 0.1651 -0.19685) (xy 0.17272 -0.18923)
						(xy 0.17907 -0.18034) (xy 0.18669 -0.17145) (xy 0.19177 -0.16256) (xy 0.19812 -0.15367) (xy 0.20828 -0.13335)
						(xy 0.21971 -0.10287) (xy 0.22225 -0.09271) (xy 0.22479 -0.08128) (xy 0.22606 -0.07112) (xy 0.2286 -0.05969)
						(xy 0.2286 -0.01651) (xy 0.22606 -0.00508) (xy 0.22479 0.00508) (xy 0.22225 0.01651) (xy 0.21971 0.02667)
						(xy 0.20828 0.05715) (xy 0.19812 0.07747) (xy 0.19177 0.08636) (xy 0.18669 0.09525) (xy 0.17907 0.10414)
						(xy 0.17272 0.11303) (xy 0.1651 0.12065) (xy 0.1651 0.7366) (xy 0.16256 0.76835) (xy 0.1524 0.8001)
						(xy 0.13716 0.82804) (xy 0.11684 0.85344) (xy 0.09144 0.87376) (xy 0.0635 0.889) (xy 0.03175 0.89916)
					)
					(width 0)
					(fill yes)
				)
			)
		)
		(pad "68" smd custom
			(at -11.549888 -4.106672 180)
			(size 0.1143 0.1143)
			(layers "F.Cu" "F.Mask" "F.Paste")
			(net "M_A_DQ27")
			(options
				(clearance outline)
				(anchor circle)
			)
			(primitives
				(gr_poly
					(pts
						(xy 0 0.9017) (xy -0.03175 0.89916) (xy -0.0635 0.889) (xy -0.09144 0.87376) (xy -0.11684 0.85344)
						(xy -0.13716 0.82804) (xy -0.1524 0.8001) (xy -0.16256 0.76835) (xy -0.1651 0.7366) (xy -0.1651 0.19685)
						(xy -0.17272 0.18923) (xy -0.17907 0.18034) (xy -0.18669 0.17145) (xy -0.19177 0.16256) (xy -0.19812 0.15367)
						(xy -0.20828 0.13335) (xy -0.21971 0.10287) (xy -0.22225 0.09271) (xy -0.22479 0.08128) (xy -0.22606 0.07112)
						(xy -0.2286 0.05969) (xy -0.2286 0.01651) (xy -0.22606 0.00508) (xy -0.22479 -0.00508) (xy -0.22225 -0.01651)
						(xy -0.21971 -0.02667) (xy -0.20828 -0.05715) (xy -0.19812 -0.07747) (xy -0.19177 -0.08636) (xy -0.18669 -0.09525)
						(xy -0.17907 -0.10414) (xy -0.17272 -0.11303) (xy -0.1651 -0.12065) (xy -0.1651 -0.7366) (xy -0.16256 -0.76835)
						(xy -0.1524 -0.8001) (xy -0.13716 -0.82804) (xy -0.11684 -0.85344) (xy -0.09144 -0.87376) (xy -0.0635 -0.889)
						(xy -0.03175 -0.89916) (xy 0 -0.9017) (xy 0.03175 -0.89916) (xy 0.0635 -0.889) (xy 0.09144 -0.87376)
						(xy 0.11684 -0.85344) (xy 0.13716 -0.82804) (xy 0.1524 -0.8001) (xy 0.16256 -0.76835) (xy 0.1651 -0.7366)
						(xy 0.1651 -0.11938) (xy 0.17272 -0.11176) (xy 0.19812 -0.0762) (xy 0.2032 -0.06604) (xy 0.20701 -0.05715)
						(xy 0.21209 -0.04699) (xy 0.2159 -0.03683) (xy 0.21844 -0.02667) (xy 0.22225 -0.01524) (xy 0.22352 -0.00508)
						(xy 0.22606 0.00508) (xy 0.22733 0.01651) (xy 0.22733 0.02667) (xy 0.2286 0.0381) (xy 0.22733 0.04953)
						(xy 0.22733 0.05969) (xy 0.22606 0.07112) (xy 0.22352 0.08128) (xy 0.22225 0.09144) (xy 0.21844 0.10287)
						(xy 0.2159 0.11303) (xy 0.21209 0.12319) (xy 0.20701 0.13335) (xy 0.2032 0.14224) (xy 0.19812 0.1524)
						(xy 0.17272 0.18796) (xy 0.1651 0.19558) (xy 0.1651 0.7366) (xy 0.16256 0.76835) (xy 0.1524 0.8001)
						(xy 0.13716 0.82804) (xy 0.11684 0.85344) (xy 0.09144 0.87376) (xy 0.0635 0.889) (xy 0.03175 0.89916)
					)
					(width 0)
					(fill yes)
				)
			)
		)
		(pad "69" smd custom
			(at -11.249914 4.106672 180)
			(size 0.1143 0.1143)
			(layers "F.Cu" "F.Mask" "F.Paste")
			(net "M_A_ECC4")
			(options
				(clearance outline)
				(anchor circle)
			)
			(primitives
				(gr_poly
					(pts
						(xy 0 0.9017) (xy -0.03175 0.89916) (xy -0.0635 0.889) (xy -0.09144 0.87376) (xy -0.11684 0.85344)
						(xy -0.13716 0.82804) (xy -0.1524 0.8001) (xy -0.16256 0.76835) (xy -0.1651 0.7366) (xy -0.1651 -0.13462)
						(xy -0.17272 -0.14224) (xy -0.19812 -0.1778) (xy -0.2032 -0.18796) (xy -0.20701 -0.19685) (xy -0.21209 -0.20701)
						(xy -0.2159 -0.21717) (xy -0.21844 -0.22733) (xy -0.22225 -0.23876) (xy -0.22352 -0.24892) (xy -0.22606 -0.25908)
						(xy -0.22733 -0.27051) (xy -0.22733 -0.28067) (xy -0.2286 -0.2921) (xy -0.22733 -0.30353) (xy -0.22733 -0.31369)
						(xy -0.22606 -0.32512) (xy -0.22352 -0.33528) (xy -0.22225 -0.34544) (xy -0.21844 -0.35687) (xy -0.2159 -0.36703)
						(xy -0.21209 -0.37719) (xy -0.20701 -0.38735) (xy -0.2032 -0.39624) (xy -0.19812 -0.4064) (xy -0.17272 -0.44196)
						(xy -0.1651 -0.44958) (xy -0.1651 -0.7366) (xy -0.16256 -0.76835) (xy -0.1524 -0.8001) (xy -0.13716 -0.82804)
						(xy -0.11684 -0.85344) (xy -0.09144 -0.87376) (xy -0.0635 -0.889) (xy -0.03175 -0.89916) (xy 0 -0.9017)
						(xy 0.03175 -0.89916) (xy 0.0635 -0.889) (xy 0.09144 -0.87376) (xy 0.11684 -0.85344) (xy 0.13716 -0.82804)
						(xy 0.1524 -0.8001) (xy 0.16256 -0.76835) (xy 0.1651 -0.7366) (xy 0.1651 -0.44958) (xy 0.17272 -0.44196)
						(xy 0.19812 -0.4064) (xy 0.2032 -0.39624) (xy 0.20701 -0.38735) (xy 0.21209 -0.37719) (xy 0.2159 -0.36703)
						(xy 0.21844 -0.35687) (xy 0.22225 -0.34544) (xy 0.22352 -0.33528) (xy 0.22606 -0.32512) (xy 0.22733 -0.31369)
						(xy 0.22733 -0.30353) (xy 0.2286 -0.2921) (xy 0.22733 -0.28067) (xy 0.22733 -0.27051) (xy 0.22606 -0.25908)
						(xy 0.22352 -0.24892) (xy 0.22225 -0.23876) (xy 0.21844 -0.22733) (xy 0.2159 -0.21717) (xy 0.21209 -0.20701)
						(xy 0.20701 -0.19685) (xy 0.2032 -0.18796) (xy 0.19812 -0.1778) (xy 0.17272 -0.14224) (xy 0.1651 -0.13462)
						(xy 0.1651 0.7366) (xy 0.16256 0.76835) (xy 0.1524 0.8001) (xy 0.13716 0.82804) (xy 0.11684 0.85344)
						(xy 0.09144 0.87376) (xy 0.0635 0.889) (xy 0.03175 0.89916)
					)
					(width 0)
					(fill yes)
				)
			)
		)
	)
)
